FILE_TYPE = MACRO_DRAWING;
SET COLOR_WIRE YELLOW;
SET COLOR_PROP ORANGE;
SET COLOR_DOT WHITE;
SET COLOR_ARC YELLOW;
SET COLOR_BODY GREEN;
SET COLOR_NOTE PURPLE;
SET PROP_DISPLAY VALUE;
SET PAGE_NUMBER P251;
FORCEADD QUANTA_TITLE_BLOCK_C..1
(5925 -2125);
FORCEPROP 1 LAST CUSTOM_TXT_CDS <NAME_2>
J 0
(2750 -2075);
FORCEPROP 1 LAST CUSTOM_TXT_CDS <NAME_1>
J 0
(2750 -1950);
FORCEPROP 1 LAST CUSTOM_TXT_CDS <Q_NUMBER>
J 0
(4522 -2022);
DISPLAY 1.212766 (4522 -2022);
FORCEPROP 1 LAST CUSTOM_TXT_CDS <Q_PROJ>
J 0
(3543 -2023);
DISPLAY 1.212766 (3543 -2023);
FORCEPROP 1 LAST CUSTOM_TXT_CDS <Q_REV>
J 0
(5741 -2022);
DISPLAY 1.212766 (5741 -2022);
FORCEPROP 1 LAST CUSTOM_TXT_CDS <CON_LAST_MODIFIED>
J 0
(4040 -2110);
DISPLAY 0.978723 (4040 -2110);
FORCEPROP 1 LAST CUSTOM_TXT_CDS <CON_PAGE_NUM> OF <CON_TOTAL_PAGES>
J 0
(5479 -2107);
DISPLAY 0.978723 (5479 -2107);
FORCEPROP 1 LAST Q_TITLE BLANK
J 0
(-3441 -2099);
DISPLAY 2.446809 (-3441 -2099);
PAINT GREEN (-3441 -2099);
FORCEPROP 1 LAST Q_DEPT 
J 1
(2162 -2076);
DISPLAY 1.957447 (2162 -2076);
PAINT GREEN (2162 -2076);
FORCEPROP 2 LAST CDS_XR_PAGE_TITLE CR-265 : @S9S_MB_2U_LIB.S9S_MB_2U(SCH_1):PAGE265
J 0
(-1965 3125);
DISPLAY 0.638298 (-1965 3125);
PAINT PINK (-1965 3125);
DISPLAY INVISIBLE (-1965 3125);
FORCEPROP 2 LAST CDS_LIB pure_quanta
J 0
(5925 -2125);
DISPLAY INVISIBLE (5925 -2125);
FORCEPROP 1 LAST CDS_LMAN_SYM_OUTLINE -9475,6775,100,-125
J 0
(5925 -2125);
DISPLAY 0.468085 (5925 -2125);
PAINT GREEN (5925 -2125);
DISPLAY INVISIBLE (5925 -2125);
FORCEPROP 1 LAST COMMENT_BODY TRUE
J 0
(5937 -2138);
DISPLAY 0.978723 (5937 -2138);
PAINT GREEN (5937 -2138);
DISPLAY INVISIBLE (5937 -2138);
FORCEPROP 2 LAST PAGE_BORDER TRUE
J 0
(-1965 3125);
DISPLAY 0.638298 (-1965 3125);
PAINT PINK (-1965 3125);
DISPLAY INVISIBLE (-1965 3125);
FORCEPROP 2 LAST CUSTOM_TXT_CDS <XR_PAGE_TITLE>
J 0
(-1965 3125);
DISPLAY 0.638298 (-1965 3125);
PAINT PINK (-1965 3125);
DISPLAY INVISIBLE (-1965 3125);
FORCEPROP 0 LAST CDS_CON_LAST_MODIFIED Thu Aug 24 16:16:23 2023
J 0
(4040 -2110);
DISPLAY INVISIBLE (4040 -2110);
FORCENOTE
THIS PAGE WAS INTENTIONALLY LEFT BLANK
(-3175 1300) 0;
DISPLAY LEFT (-3175 1300);
DISPLAY 4.914894 (-3175 1300);
QUIT
